(kicad_pcb
	(version 20260206)
	(generator "pcbnew")
	(generator_version "10.0")
	(general
		(thickness 1.6)
		(legacy_teardrops no)
	)
	(paper "A4")
	(title_block
		(title "Wiwynn_Tioga_Pass_MB.brd")
		(comment 1 "Tioga Pass / footprints 220-226 of 4770")
	)
	(layers
		(0 "F.Cu" signal "TOP")
		(4 "In1.Cu" signal "L2GND")
		(6 "In2.Cu" signal "L3")
		(8 "In3.Cu" signal "L4GND")
		(10 "In4.Cu" signal "L5")
		(12 "In5.Cu" signal "L6GND")
		(14 "In6.Cu" signal "L7VCC")
		(16 "In7.Cu" signal "L8VCC")
		(18 "In8.Cu" signal "L9GND")
		(20 "In9.Cu" signal "L10")
		(22 "In10.Cu" signal "L11GND")
		(24 "In11.Cu" signal "L12")
		(26 "In12.Cu" signal "L13GND")
		(2 "B.Cu" signal "BOTTOM")
		(9 "F.Adhes" user "F.Adhesive")
		(11 "B.Adhes" user "B.Adhesive")
		(13 "F.Paste" user "Package Geometry/Pastemask Top")
		(15 "B.Paste" user "Package Geometry/Pastemask Bottom")
		(5 "F.SilkS" user "Ref Des/Silkscreen Top")
		(7 "B.SilkS" user "Ref Des/Silkscreen Bottom")
		(1 "F.Mask" user "Board Geometry/Soldermask Top")
		(3 "B.Mask" user "Board Geometry/Soldermask Bottom")
		(17 "Dwgs.User" user "User.Drawings")
		(19 "Cmts.User" user "User.Comments")
		(21 "Eco1.User" user "User.Eco1")
		(23 "Eco2.User" user "User.Eco2")
		(25 "Edge.Cuts" user "Board Geometry/Outline")
		(27 "Margin" user)
		(31 "F.CrtYd" user "Package Geometry/Place Bound Top")
		(29 "B.CrtYd" user "Package Geometry/Place Bound Bottom")
		(35 "F.Fab" user "Ref Des/Assembly Top")
		(33 "B.Fab" user "Ref Des/Assembly Bottom")
	)
	(footprint ""
		(layer "F.Cu")
		(at 489.712 -50.6349)
		(property "Reference" "R9E4"
			(at 0 0 0)
			(layer "F.SilkS")
			(hide yes)
			(effects
				(font
					(size 1.27 1.27)
				)
			)
		)
		(property "Value" ""
			(at 0 0 0)
			(layer "F.Fab")
			(effects
				(font
					(size 1.27 1.27)
				)
			)
		)
		(duplicate_pad_numbers_are_jumpers no)
		(fp_poly
			(pts
				(xy -0.2794 -0.1016) (xy 0.2794 -0.1016) (xy 0.2794 0.9906) (xy -0.2794 0.9906)
			)
			(stroke
				(width 0)
				(type default)
			)
			(fill no)
			(layer "F.CrtYd")
		)
		(fp_line
			(start -0.2794 -0.1016)
			(end -0.2794 0.9906)
			(stroke
				(width 0.1)
				(type default)
			)
			(layer "F.Fab")
		)
		(fp_line
			(start -0.2794 0.9906)
			(end 0.2794 0.9906)
			(stroke
				(width 0.1)
				(type default)
			)
			(layer "F.Fab")
		)
		(fp_line
			(start 0.2794 -0.1016)
			(end -0.2794 -0.1016)
			(stroke
				(width 0.1)
				(type default)
			)
			(layer "F.Fab")
		)
		(fp_line
			(start 0.2794 0.9906)
			(end 0.2794 -0.1016)
			(stroke
				(width 0.1)
				(type default)
			)
			(layer "F.Fab")
		)
		(pad "1" smd rect
			(at 0 0)
			(size 0.508 0.508)
			(layers "F.Cu" "F.Mask" "F.Paste")
			(net "P3V3_STBY")
		)
		(pad "2" smd rect
			(at 0 0.889)
			(size 0.508 0.508)
			(layers "F.Cu" "F.Mask" "F.Paste")
			(net "RST_PLTRST_SPRV_R_N")
		)
		(zone
			(layer "F.Cu")
			(hatch none 0.5)
			(connect_pads
				(clearance 0)
			)
			(min_thickness 0.25)
			(keepout
				(tracks allowed)
				(vias not_allowed)
				(pads allowed)
				(copperpour not_allowed)
				(footprints allowed)
			)
			(placement
				(enabled no)
				(sheetname "")
			)
			(fill
				(thermal_gap 0.5)
				(thermal_bridge_width 0.5)
				(island_removal_mode 0)
			)
			(polygon
				(pts
					(xy 489.458 -50.3809) (xy 489.966 -50.3809) (xy 489.966 -49.9999) (xy 489.458 -49.9999)
				)
			)
		)
		(zone
			(layer "F.Cu")
			(hatch none 0.5)
			(connect_pads
				(clearance 0)
			)
			(min_thickness 0.25)
			(keepout
				(tracks not_allowed)
				(vias allowed)
				(pads allowed)
				(copperpour not_allowed)
				(footprints allowed)
			)
			(placement
				(enabled no)
				(sheetname "")
			)
			(fill
				(thermal_gap 0.5)
				(thermal_bridge_width 0.5)
				(island_removal_mode 0)
			)
			(polygon
				(pts
					(xy 489.458 -49.9999) (xy 489.966 -49.9999) (xy 489.966 -50.3809) (xy 489.458 -50.3809)
				)
			)
		)
	)
	(footprint ""
		(layer "F.Cu")
		(at 489.3945 -143.876268 90)
		(property "Reference" "R1L25"
			(at 0 0 90)
			(layer "F.SilkS")
			(hide yes)
			(effects
				(font
					(size 1.27 1.27)
				)
			)
		)
		(property "Value" ""
			(at 0 0 90)
			(layer "F.Fab")
			(effects
				(font
					(size 1.27 1.27)
				)
			)
		)
		(duplicate_pad_numbers_are_jumpers no)
		(fp_poly
			(pts
				(xy -0.2794 -0.1016) (xy 0.2794 -0.1016) (xy 0.2794 0.9906) (xy -0.2794 0.9906)
			)
			(stroke
				(width 0)
				(type default)
			)
			(fill no)
			(layer "F.CrtYd")
		)
		(fp_line
			(start 0.2794 -0.1016)
			(end -0.2794 -0.1016)
			(stroke
				(width 0.1)
				(type default)
			)
			(layer "F.Fab")
		)
		(fp_line
			(start -0.2794 -0.1016)
			(end -0.2794 0.9906)
			(stroke
				(width 0.1)
				(type default)
			)
			(layer "F.Fab")
		)
		(fp_line
			(start 0.2794 0.9906)
			(end 0.2794 -0.1016)
			(stroke
				(width 0.1)
				(type default)
			)
			(layer "F.Fab")
		)
		(fp_line
			(start -0.2794 0.9906)
			(end 0.2794 0.9906)
			(stroke
				(width 0.1)
				(type default)
			)
			(layer "F.Fab")
		)
		(pad "1" smd rect
			(at 0 0 90)
			(size 0.508 0.508)
			(layers "F.Cu" "F.Mask" "F.Paste")
			(net "LED_POSTCODE_2")
		)
		(pad "2" smd rect
			(at 0 0.889 90)
			(size 0.508 0.508)
			(layers "F.Cu" "F.Mask" "F.Paste")
			(net "LED_POSTCODE_2_R")
		)
		(zone
			(layer "F.Cu")
			(hatch none 0.5)
			(connect_pads
				(clearance 0)
			)
			(min_thickness 0.25)
			(keepout
				(tracks allowed)
				(vias not_allowed)
				(pads allowed)
				(copperpour not_allowed)
				(footprints allowed)
			)
			(placement
				(enabled no)
				(sheetname "")
			)
			(fill
				(thermal_gap 0.5)
				(thermal_bridge_width 0.5)
				(island_removal_mode 0)
			)
			(polygon
				(pts
					(xy 489.6485 -143.622268) (xy 489.6485 -144.130268) (xy 490.0295 -144.130268) (xy 490.0295 -143.622268)
				)
			)
		)
		(zone
			(layer "F.Cu")
			(hatch none 0.5)
			(connect_pads
				(clearance 0)
			)
			(min_thickness 0.25)
			(keepout
				(tracks not_allowed)
				(vias allowed)
				(pads allowed)
				(copperpour not_allowed)
				(footprints allowed)
			)
			(placement
				(enabled no)
				(sheetname "")
			)
			(fill
				(thermal_gap 0.5)
				(thermal_bridge_width 0.5)
				(island_removal_mode 0)
			)
			(polygon
				(pts
					(xy 490.0295 -143.622268) (xy 490.0295 -144.130268) (xy 489.6485 -144.130268) (xy 489.6485 -143.622268)
				)
			)
		)
	)
	(footprint ""
		(layer "F.Cu")
		(at 401.13966 -151.72436 -90)
		(property "Reference" "R8A5"
			(at 0 0 270)
			(layer "F.SilkS")
			(hide yes)
			(effects
				(font
					(size 1.27 1.27)
				)
			)
		)
		(property "Value" ""
			(at 0 0 270)
			(layer "F.Fab")
			(effects
				(font
					(size 1.27 1.27)
				)
			)
		)
		(duplicate_pad_numbers_are_jumpers no)
		(fp_poly
			(pts
				(xy -0.2794 -0.1016) (xy 0.2794 -0.1016) (xy 0.2794 0.9906) (xy -0.2794 0.9906)
			)
			(stroke
				(width 0)
				(type default)
			)
			(fill no)
			(layer "F.CrtYd")
		)
		(fp_line
			(start -0.2794 0.9906)
			(end 0.2794 0.9906)
			(stroke
				(width 0.1)
				(type default)
			)
			(layer "F.Fab")
		)
		(fp_line
			(start 0.2794 0.9906)
			(end 0.2794 -0.1016)
			(stroke
				(width 0.1)
				(type default)
			)
			(layer "F.Fab")
		)
		(fp_line
			(start -0.2794 -0.1016)
			(end -0.2794 0.9906)
			(stroke
				(width 0.1)
				(type default)
			)
			(layer "F.Fab")
		)
		(fp_line
			(start 0.2794 -0.1016)
			(end -0.2794 -0.1016)
			(stroke
				(width 0.1)
				(type default)
			)
			(layer "F.Fab")
		)
		(pad "1" smd rect
			(at 0 0 270)
			(size 0.508 0.508)
			(layers "F.Cu" "F.Mask" "F.Paste")
			(net "P3V3_STBY")
		)
		(pad "2" smd rect
			(at 0 0.889 270)
			(size 0.508 0.508)
			(layers "F.Cu" "F.Mask" "F.Paste")
			(net "IRQ_PVNN_PCH_VRHOT_N")
		)
		(zone
			(layer "F.Cu")
			(hatch none 0.5)
			(connect_pads
				(clearance 0)
			)
			(min_thickness 0.25)
			(keepout
				(tracks not_allowed)
				(vias allowed)
				(pads allowed)
				(copperpour not_allowed)
				(footprints allowed)
			)
			(placement
				(enabled no)
				(sheetname "")
			)
			(fill
				(thermal_gap 0.5)
				(thermal_bridge_width 0.5)
				(island_removal_mode 0)
			)
			(polygon
				(pts
					(xy 400.50466 -151.97836) (xy 400.50466 -151.47036) (xy 400.88566 -151.47036) (xy 400.88566 -151.97836)
				)
			)
		)
		(zone
			(layer "F.Cu")
			(hatch none 0.5)
			(connect_pads
				(clearance 0)
			)
			(min_thickness 0.25)
			(keepout
				(tracks allowed)
				(vias not_allowed)
				(pads allowed)
				(copperpour not_allowed)
				(footprints allowed)
			)
			(placement
				(enabled no)
				(sheetname "")
			)
			(fill
				(thermal_gap 0.5)
				(thermal_bridge_width 0.5)
				(island_removal_mode 0)
			)
			(polygon
				(pts
					(xy 400.88566 -151.97836) (xy 400.88566 -151.47036) (xy 400.50466 -151.47036) (xy 400.50466 -151.97836)
				)
			)
		)
	)
	(footprint ""
		(layer "F.Cu")
		(at 176.0728 -106.74985)
		(property "Reference" "R4C11"
			(at 0 0 0)
			(layer "F.SilkS")
			(hide yes)
			(effects
				(font
					(size 1.27 1.27)
				)
			)
		)
		(property "Value" ""
			(at 0 0 0)
			(layer "F.Fab")
			(effects
				(font
					(size 1.27 1.27)
				)
			)
		)
		(duplicate_pad_numbers_are_jumpers no)
		(fp_poly
			(pts
				(xy -0.2794 -0.1016) (xy 0.2794 -0.1016) (xy 0.2794 0.9906) (xy -0.2794 0.9906)
			)
			(stroke
				(width 0)
				(type default)
			)
			(fill no)
			(layer "F.CrtYd")
		)
		(fp_line
			(start -0.2794 -0.1016)
			(end -0.2794 0.9906)
			(stroke
				(width 0.1)
				(type default)
			)
			(layer "F.Fab")
		)
		(fp_line
			(start -0.2794 0.9906)
			(end 0.2794 0.9906)
			(stroke
				(width 0.1)
				(type default)
			)
			(layer "F.Fab")
		)
		(fp_line
			(start 0.2794 -0.1016)
			(end -0.2794 -0.1016)
			(stroke
				(width 0.1)
				(type default)
			)
			(layer "F.Fab")
		)
		(fp_line
			(start 0.2794 0.9906)
			(end 0.2794 -0.1016)
			(stroke
				(width 0.1)
				(type default)
			)
			(layer "F.Fab")
		)
		(pad "1" smd rect
			(at 0 0)
			(size 0.508 0.508)
			(layers "F.Cu" "F.Mask" "F.Paste")
			(net "VR_PVCCMCP_CPU1_XADDR2")
		)
		(pad "2" smd rect
			(at 0 0.889)
			(size 0.508 0.508)
			(layers "F.Cu" "F.Mask" "F.Paste")
			(net "GND")
		)
		(zone
			(layer "F.Cu")
			(hatch none 0.5)
			(connect_pads
				(clearance 0)
			)
			(min_thickness 0.25)
			(keepout
				(tracks allowed)
				(vias not_allowed)
				(pads allowed)
				(copperpour not_allowed)
				(footprints allowed)
			)
			(placement
				(enabled no)
				(sheetname "")
			)
			(fill
				(thermal_gap 0.5)
				(thermal_bridge_width 0.5)
				(island_removal_mode 0)
			)
			(polygon
				(pts
					(xy 175.8188 -106.49585) (xy 176.3268 -106.49585) (xy 176.3268 -106.11485) (xy 175.8188 -106.11485)
				)
			)
		)
		(zone
			(layer "F.Cu")
			(hatch none 0.5)
			(connect_pads
				(clearance 0)
			)
			(min_thickness 0.25)
			(keepout
				(tracks not_allowed)
				(vias allowed)
				(pads allowed)
				(copperpour not_allowed)
				(footprints allowed)
			)
			(placement
				(enabled no)
				(sheetname "")
			)
			(fill
				(thermal_gap 0.5)
				(thermal_bridge_width 0.5)
				(island_removal_mode 0)
			)
			(polygon
				(pts
					(xy 175.8188 -106.11485) (xy 176.3268 -106.11485) (xy 176.3268 -106.49585) (xy 175.8188 -106.49585)
				)
			)
		)
	)
	(footprint ""
		(layer "F.Cu")
		(at 167.386 -86.868 180)
		(property "Reference" "R4D3"
			(at 0 0 180)
			(layer "F.SilkS")
			(hide yes)
			(effects
				(font
					(size 1.27 1.27)
				)
			)
		)
		(property "Value" ""
			(at 0 0 180)
			(layer "F.Fab")
			(effects
				(font
					(size 1.27 1.27)
				)
			)
		)
		(duplicate_pad_numbers_are_jumpers no)
		(fp_poly
			(pts
				(xy -0.2794 -0.1016) (xy 0.2794 -0.1016) (xy 0.2794 0.9906) (xy -0.2794 0.9906)
			)
			(stroke
				(width 0)
				(type default)
			)
			(fill no)
			(layer "F.CrtYd")
		)
		(fp_line
			(start 0.2794 0.9906)
			(end 0.2794 -0.1016)
			(stroke
				(width 0.1)
				(type default)
			)
			(layer "F.Fab")
		)
		(fp_line
			(start 0.2794 -0.1016)
			(end -0.2794 -0.1016)
			(stroke
				(width 0.1)
				(type default)
			)
			(layer "F.Fab")
		)
		(fp_line
			(start -0.2794 0.9906)
			(end 0.2794 0.9906)
			(stroke
				(width 0.1)
				(type default)
			)
			(layer "F.Fab")
		)
		(fp_line
			(start -0.2794 -0.1016)
			(end -0.2794 0.9906)
			(stroke
				(width 0.1)
				(type default)
			)
			(layer "F.Fab")
		)
		(pad "1" smd rect
			(at 0 0 180)
			(size 0.508 0.508)
			(layers "F.Cu" "F.Mask" "F.Paste")
			(net "CLK_100M_CPU1_BCLK0_R_DN")
		)
		(pad "2" smd rect
			(at 0 0.889 180)
			(size 0.508 0.508)
			(layers "F.Cu" "F.Mask" "F.Paste")
			(net "CLK_100M_CPU1_BCLK0_DN")
		)
		(zone
			(layer "F.Cu")
			(hatch none 0.5)
			(connect_pads
				(clearance 0)
			)
			(min_thickness 0.25)
			(keepout
				(tracks not_allowed)
				(vias allowed)
				(pads allowed)
				(copperpour not_allowed)
				(footprints allowed)
			)
			(placement
				(enabled no)
				(sheetname "")
			)
			(fill
				(thermal_gap 0.5)
				(thermal_bridge_width 0.5)
				(island_removal_mode 0)
			)
			(polygon
				(pts
					(xy 167.64 -87.503) (xy 167.132 -87.503) (xy 167.132 -87.122) (xy 167.64 -87.122)
				)
			)
		)
		(zone
			(layer "F.Cu")
			(hatch none 0.5)
			(connect_pads
				(clearance 0)
			)
			(min_thickness 0.25)
			(keepout
				(tracks allowed)
				(vias not_allowed)
				(pads allowed)
				(copperpour not_allowed)
				(footprints allowed)
			)
			(placement
				(enabled no)
				(sheetname "")
			)
			(fill
				(thermal_gap 0.5)
				(thermal_bridge_width 0.5)
				(island_removal_mode 0)
			)
			(polygon
				(pts
					(xy 167.64 -87.122) (xy 167.132 -87.122) (xy 167.132 -87.503) (xy 167.64 -87.503)
				)
			)
		)
	)
	(footprint ""
		(layer "F.Cu")
		(at 258.208272 -81.560416)
		(property "Reference" "C5D13"
			(at 0 0 0)
			(layer "F.SilkS")
			(hide yes)
			(effects
				(font
					(size 1.27 1.27)
				)
			)
		)
		(property "Value" ""
			(at 0 0 0)
			(layer "F.Fab")
			(effects
				(font
					(size 1.27 1.27)
				)
			)
		)
		(duplicate_pad_numbers_are_jumpers no)
		(fp_poly
			(pts
				(xy -0.4953 -0.2032) (xy 0.4953 -0.2032) (xy 0.4953 1.6002) (xy -0.4953 1.6002)
			)
			(stroke
				(width 0)
				(type default)
			)
			(fill no)
			(layer "F.CrtYd")
		)
		(fp_line
			(start -0.4953 -0.2032)
			(end 0.4953 -0.2032)
			(stroke
				(width 0.1)
				(type default)
			)
			(layer "F.Fab")
		)
		(fp_line
			(start -0.4953 1.6002)
			(end -0.4953 -0.2032)
			(stroke
				(width 0.1)
				(type default)
			)
			(layer "F.Fab")
		)
		(fp_line
			(start 0.4953 -0.2032)
			(end 0.4953 1.6002)
			(stroke
				(width 0.1)
				(type default)
			)
			(layer "F.Fab")
		)
		(fp_line
			(start 0.4953 1.6002)
			(end -0.4953 1.6002)
			(stroke
				(width 0.1)
				(type default)
			)
			(layer "F.Fab")
		)
		(pad "1" smd rect
			(at 0 0)
			(size 0.762 0.889)
			(layers "F.Cu" "F.Mask" "F.Paste")
			(net "PVSA_CPU0")
		)
		(pad "2" smd rect
			(at 0 1.397)
			(size 0.762 0.889)
			(layers "F.Cu" "F.Mask" "F.Paste")
			(net "GND")
		)
		(zone
			(layer "F.Cu")
			(hatch none 0.5)
			(connect_pads
				(clearance 0)
			)
			(min_thickness 0.25)
			(keepout
				(tracks not_allowed)
				(vias allowed)
				(pads allowed)
				(copperpour not_allowed)
				(footprints allowed)
			)
			(placement
				(enabled no)
				(sheetname "")
			)
			(fill
				(thermal_gap 0.5)
				(thermal_bridge_width 0.5)
				(island_removal_mode 0)
			)
			(polygon
				(pts
					(xy 257.827272 -81.115916) (xy 258.589272 -81.115916) (xy 258.589272 -80.607916) (xy 257.827272 -80.607916)
				)
			)
		)
	)
	(footprint ""
		(layer "F.Cu")
		(at 162.871912 -63.829184)
		(property "Reference" "R3E1"
			(at 0 0 0)
			(layer "F.SilkS")
			(hide yes)
			(effects
				(font
					(size 1.27 1.27)
				)
			)
		)
		(property "Value" ""
			(at 0 0 0)
			(layer "F.Fab")
			(effects
				(font
					(size 1.27 1.27)
				)
			)
		)
		(duplicate_pad_numbers_are_jumpers no)
		(fp_poly
			(pts
				(xy -0.2794 -0.1016) (xy 0.2794 -0.1016) (xy 0.2794 0.9906) (xy -0.2794 0.9906)
			)
			(stroke
				(width 0)
				(type default)
			)
			(fill no)
			(layer "F.CrtYd")
		)
		(fp_line
			(start -0.2794 -0.1016)
			(end -0.2794 0.9906)
			(stroke
				(width 0.1)
				(type default)
			)
			(layer "F.Fab")
		)
		(fp_line
			(start -0.2794 0.9906)
			(end 0.2794 0.9906)
			(stroke
				(width 0.1)
				(type default)
			)
			(layer "F.Fab")
		)
		(fp_line
			(start 0.2794 -0.1016)
			(end -0.2794 -0.1016)
			(stroke
				(width 0.1)
				(type default)
			)
			(layer "F.Fab")
		)
		(fp_line
			(start 0.2794 0.9906)
			(end 0.2794 -0.1016)
			(stroke
				(width 0.1)
				(type default)
			)
			(layer "F.Fab")
		)
		(pad "1" smd rect
			(at 0 0)
			(size 0.508 0.508)
			(layers "F.Cu" "F.Mask" "F.Paste")
			(net "VSENSE_PVCCIO_CPU1_AVSP")
		)
		(pad "2" smd rect
			(at 0 0.889)
			(size 0.508 0.508)
			(layers "F.Cu" "F.Mask" "F.Paste")
			(net "PVCCIO_CPU1")
		)
		(zone
			(layer "F.Cu")
			(hatch none 0.5)
			(connect_pads
				(clearance 0)
			)
			(min_thickness 0.25)
			(keepout
				(tracks allowed)
				(vias not_allowed)
				(pads allowed)
				(copperpour not_allowed)
				(footprints allowed)
			)
			(placement
				(enabled no)
				(sheetname "")
			)
			(fill
				(thermal_gap 0.5)
				(thermal_bridge_width 0.5)
				(island_removal_mode 0)
			)
			(polygon
				(pts
					(xy 162.617912 -63.575184) (xy 163.125912 -63.575184) (xy 163.125912 -63.194184) (xy 162.617912 -63.194184)
				)
			)
		)
		(zone
			(layer "F.Cu")
			(hatch none 0.5)
			(connect_pads
				(clearance 0)
			)
			(min_thickness 0.25)
			(keepout
				(tracks not_allowed)
				(vias allowed)
				(pads allowed)
				(copperpour not_allowed)
				(footprints allowed)
			)
			(placement
				(enabled no)
				(sheetname "")
			)
			(fill
				(thermal_gap 0.5)
				(thermal_bridge_width 0.5)
				(island_removal_mode 0)
			)
			(polygon
				(pts
					(xy 162.617912 -63.194184) (xy 163.125912 -63.194184) (xy 163.125912 -63.575184) (xy 162.617912 -63.575184)
				)
			)
		)
	)
)
